(kicad_pcb
	(version 20260206)
	(generator "pcbnew")
	(generator_version "10.0")
	(general
		(thickness 1.6)
		(legacy_teardrops no)
	)
	(paper "A4")
	(title_block
		(title "03242023_DA0F0TMBIJ0_F0T_Motherboard_J_brd_V01_OCP.brd")
		(comment 1 "Grand Teton / footprints 5526-5532 of 6105")
	)
	(layers
		(0 "F.Cu" signal "TOP")
		(4 "In1.Cu" signal "GND")
		(6 "In2.Cu" signal "IN1")
		(8 "In3.Cu" signal "GND1")
		(10 "In4.Cu" signal "IN2")
		(12 "In5.Cu" signal "GND2")
		(14 "In6.Cu" signal "IN3")
		(16 "In7.Cu" signal "GND3")
		(18 "In8.Cu" signal "VCC")
		(20 "In9.Cu" signal "VCC1")
		(22 "In10.Cu" signal "GND4")
		(24 "In11.Cu" signal "IN4")
		(26 "In12.Cu" signal "GND5")
		(28 "In13.Cu" signal "IN5")
		(30 "In14.Cu" signal "GND6")
		(32 "In15.Cu" signal "IN6")
		(34 "In16.Cu" signal "GND7")
		(2 "B.Cu" signal "BOTTOM")
		(9 "F.Adhes" user "F.Adhesive")
		(11 "B.Adhes" user "B.Adhesive")
		(13 "F.Paste" user "Package Geometry/Pastemask Top")
		(15 "B.Paste" user "Package Geometry/Pastemask Bottom")
		(5 "F.SilkS" user "Ref Des/Silkscreen Top")
		(7 "B.SilkS" user "Ref Des/Silkscreen Bottom")
		(1 "F.Mask" user "Board Geometry/Soldermask Top")
		(3 "B.Mask" user "Board Geometry/Soldermask Bottom")
		(17 "Dwgs.User" user "User.Drawings")
		(19 "Cmts.User" user "User.Comments")
		(21 "Eco1.User" user "User.Eco1")
		(23 "Eco2.User" user "User.Eco2")
		(25 "Edge.Cuts" user "Board Geometry/Outline")
		(27 "Margin" user)
		(31 "F.CrtYd" user "Package Geometry/Place Bound Top")
		(29 "B.CrtYd" user "Package Geometry/Place Bound Bottom")
		(35 "F.Fab" user "Ref Des/Assembly Top")
		(33 "B.Fab" user "Ref Des/Assembly Bottom")
	)
	(footprint ""
		(layer "B.Cu")
		(at 27.0383 -125.342396)
		(property "Reference" "PR283"
			(at 0 0 0)
			(layer "B.SilkS")
			(hide yes)
			(effects
				(font
					(size 1.27 1.27)
				)
				(justify mirror)
			)
		)
		(property "Value" ""
			(at 0 0 0)
			(layer "B.Fab")
			(effects
				(font
					(size 1.27 1.27)
				)
				(justify mirror)
			)
		)
		(duplicate_pad_numbers_are_jumpers no)
		(fp_line
			(start -0.7874 -0.4064)
			(end -0.7874 0.4064)
			(stroke
				(width 0.1524)
				(type default)
			)
			(layer "B.SilkS")
		)
		(fp_line
			(start -0.7874 0.4064)
			(end 0.7874 0.4064)
			(stroke
				(width 0.1524)
				(type default)
			)
			(layer "B.SilkS")
		)
		(fp_line
			(start 0.7874 -0.4064)
			(end -0.7874 -0.4064)
			(stroke
				(width 0.1524)
				(type default)
			)
			(layer "B.SilkS")
		)
		(fp_line
			(start 0.7874 0.4064)
			(end 0.7874 -0.4064)
			(stroke
				(width 0.1524)
				(type default)
			)
			(layer "B.SilkS")
		)
		(fp_line
			(start -0.67945 -0.3048)
			(end -0.67945 0.3048)
			(stroke
				(width 0.1)
				(type default)
			)
			(layer "B.Fab")
		)
		(fp_line
			(start -0.67945 0.3048)
			(end -0.120396 0.3048)
			(stroke
				(width 0.1)
				(type default)
			)
			(layer "B.Fab")
		)
		(fp_line
			(start -0.12065 -0.3048)
			(end -0.67945 -0.3048)
			(stroke
				(width 0.1)
				(type default)
			)
			(layer "B.Fab")
		)
		(fp_line
			(start -0.12065 -0.2794)
			(end -0.12065 -0.3048)
			(stroke
				(width 0.1)
				(type default)
			)
			(layer "B.Fab")
		)
		(fp_line
			(start -0.120396 0.2794)
			(end 0.12065 0.2794)
			(stroke
				(width 0.1)
				(type default)
			)
			(layer "B.Fab")
		)
		(fp_line
			(start -0.120396 0.3048)
			(end -0.120396 0.2794)
			(stroke
				(width 0.1)
				(type default)
			)
			(layer "B.Fab")
		)
		(fp_line
			(start 0.12065 -0.305054)
			(end 0.12065 -0.2794)
			(stroke
				(width 0.1)
				(type default)
			)
			(layer "B.Fab")
		)
		(fp_line
			(start 0.12065 -0.2794)
			(end -0.12065 -0.2794)
			(stroke
				(width 0.1)
				(type default)
			)
			(layer "B.Fab")
		)
		(fp_line
			(start 0.12065 0.2794)
			(end 0.12065 0.3048)
			(stroke
				(width 0.1)
				(type default)
			)
			(layer "B.Fab")
		)
		(fp_line
			(start 0.12065 0.3048)
			(end 0.67945 0.3048)
			(stroke
				(width 0.1)
				(type default)
			)
			(layer "B.Fab")
		)
		(fp_line
			(start 0.67945 -0.305054)
			(end 0.12065 -0.305054)
			(stroke
				(width 0.1)
				(type default)
			)
			(layer "B.Fab")
		)
		(fp_line
			(start 0.67945 0.3048)
			(end 0.67945 -0.305054)
			(stroke
				(width 0.1)
				(type default)
			)
			(layer "B.Fab")
		)
		(pad "1" smd circle
			(at 0.40005 0 180)
			(size 0 0)
			(layers "B.Cu" "B.Mask" "B.Paste")
			(net "PVCCINFAON_CPU1_VCC")
		)
		(pad "2" smd circle
			(at -0.40005 0 180)
			(size 0 0)
			(layers "B.Cu" "B.Mask" "B.Paste")
			(net "P3V3_AUX")
		)
	)
	(footprint ""
		(layer "B.Cu")
		(at 297.419776 -46.40199)
		(property "Reference" "C1246"
			(at 0 0 0)
			(layer "B.SilkS")
			(hide yes)
			(effects
				(font
					(size 1.27 1.27)
				)
				(justify mirror)
			)
		)
		(property "Value" ""
			(at 0 0 0)
			(layer "B.Fab")
			(effects
				(font
					(size 1.27 1.27)
				)
				(justify mirror)
			)
		)
		(duplicate_pad_numbers_are_jumpers no)
		(fp_line
			(start -1.524 -0.762)
			(end -1.524 0.762)
			(stroke
				(width 0.1524)
				(type default)
			)
			(layer "B.SilkS")
		)
		(fp_line
			(start -1.524 0.762)
			(end 1.524 0.762)
			(stroke
				(width 0.1524)
				(type default)
			)
			(layer "B.SilkS")
		)
		(fp_line
			(start 1.524 -0.762)
			(end -1.524 -0.762)
			(stroke
				(width 0.1524)
				(type default)
			)
			(layer "B.SilkS")
		)
		(fp_line
			(start 1.524 0.762)
			(end 1.524 -0.762)
			(stroke
				(width 0.1524)
				(type default)
			)
			(layer "B.SilkS")
		)
		(fp_line
			(start -1.1049 -0.724916)
			(end 1.1049 -0.724916)
			(stroke
				(width 0.1)
				(type default)
			)
			(layer "B.Fab")
		)
		(fp_line
			(start -1.1049 0.724916)
			(end -1.1049 -0.724916)
			(stroke
				(width 0.1)
				(type default)
			)
			(layer "B.Fab")
		)
		(fp_line
			(start 1.1049 -0.724916)
			(end 1.1049 0.724916)
			(stroke
				(width 0.1)
				(type default)
			)
			(layer "B.Fab")
		)
		(fp_line
			(start 1.1049 0.724916)
			(end -1.1049 0.724916)
			(stroke
				(width 0.1)
				(type default)
			)
			(layer "B.Fab")
		)
		(pad "1" smd rect
			(at 0.889 0)
			(size 1.016 1.27)
			(layers "B.Cu" "B.Mask" "B.Paste")
			(net "P1V05_PCH_AUX")
		)
		(pad "2" smd rect
			(at -0.889 0)
			(size 1.016 1.27)
			(layers "B.Cu" "B.Mask" "B.Paste")
			(net "GND")
		)
	)
	(footprint ""
		(layer "B.Cu")
		(at 369.49888 -38.953948 180)
		(property "Reference" "R4112"
			(at 0 0 0)
			(layer "B.SilkS")
			(hide yes)
			(effects
				(font
					(size 1.27 1.27)
				)
				(justify mirror)
			)
		)
		(property "Value" ""
			(at 0 0 0)
			(layer "B.Fab")
			(effects
				(font
					(size 1.27 1.27)
				)
				(justify mirror)
			)
		)
		(duplicate_pad_numbers_are_jumpers no)
		(fp_line
			(start 0.7874 0.4064)
			(end 0.7874 -0.4064)
			(stroke
				(width 0.1524)
				(type default)
			)
			(layer "B.SilkS")
		)
		(fp_line
			(start 0.7874 -0.4064)
			(end -0.7874 -0.4064)
			(stroke
				(width 0.1524)
				(type default)
			)
			(layer "B.SilkS")
		)
		(fp_line
			(start -0.7874 0.4064)
			(end 0.7874 0.4064)
			(stroke
				(width 0.1524)
				(type default)
			)
			(layer "B.SilkS")
		)
		(fp_line
			(start -0.7874 -0.4064)
			(end -0.7874 0.4064)
			(stroke
				(width 0.1524)
				(type default)
			)
			(layer "B.SilkS")
		)
		(fp_line
			(start 0.67945 0.3048)
			(end 0.67945 -0.305054)
			(stroke
				(width 0.1)
				(type default)
			)
			(layer "B.Fab")
		)
		(fp_line
			(start 0.67945 -0.305054)
			(end 0.12065 -0.305054)
			(stroke
				(width 0.1)
				(type default)
			)
			(layer "B.Fab")
		)
		(fp_line
			(start 0.12065 0.3048)
			(end 0.67945 0.3048)
			(stroke
				(width 0.1)
				(type default)
			)
			(layer "B.Fab")
		)
		(fp_line
			(start 0.12065 0.2794)
			(end 0.12065 0.3048)
			(stroke
				(width 0.1)
				(type default)
			)
			(layer "B.Fab")
		)
		(fp_line
			(start 0.12065 -0.2794)
			(end -0.12065 -0.2794)
			(stroke
				(width 0.1)
				(type default)
			)
			(layer "B.Fab")
		)
		(fp_line
			(start 0.12065 -0.305054)
			(end 0.12065 -0.2794)
			(stroke
				(width 0.1)
				(type default)
			)
			(layer "B.Fab")
		)
		(fp_line
			(start -0.120396 0.3048)
			(end -0.120396 0.2794)
			(stroke
				(width 0.1)
				(type default)
			)
			(layer "B.Fab")
		)
		(fp_line
			(start -0.120396 0.2794)
			(end 0.12065 0.2794)
			(stroke
				(width 0.1)
				(type default)
			)
			(layer "B.Fab")
		)
		(fp_line
			(start -0.12065 -0.2794)
			(end -0.12065 -0.3048)
			(stroke
				(width 0.1)
				(type default)
			)
			(layer "B.Fab")
		)
		(fp_line
			(start -0.12065 -0.3048)
			(end -0.67945 -0.3048)
			(stroke
				(width 0.1)
				(type default)
			)
			(layer "B.Fab")
		)
		(fp_line
			(start -0.67945 0.3048)
			(end -0.120396 0.3048)
			(stroke
				(width 0.1)
				(type default)
			)
			(layer "B.Fab")
		)
		(fp_line
			(start -0.67945 -0.3048)
			(end -0.67945 0.3048)
			(stroke
				(width 0.1)
				(type default)
			)
			(layer "B.Fab")
		)
		(pad "1" smd circle
			(at 0.40005 0)
			(size 0 0)
			(layers "B.Cu" "B.Mask" "B.Paste")
			(net "PD_PCH_GPP_E_12")
		)
		(pad "2" smd circle
			(at -0.40005 0)
			(size 0 0)
			(layers "B.Cu" "B.Mask" "B.Paste")
			(net "GND")
		)
	)
	(footprint ""
		(layer "B.Cu")
		(at 218.83751 -68.38188 180)
		(property "Reference" "R3959"
			(at 0 0 0)
			(layer "B.SilkS")
			(hide yes)
			(effects
				(font
					(size 1.27 1.27)
				)
				(justify mirror)
			)
		)
		(property "Value" ""
			(at 0 0 0)
			(layer "B.Fab")
			(effects
				(font
					(size 1.27 1.27)
				)
				(justify mirror)
			)
		)
		(duplicate_pad_numbers_are_jumpers no)
		(fp_line
			(start 0.7874 0.4064)
			(end 0.7874 -0.4064)
			(stroke
				(width 0.1524)
				(type default)
			)
			(layer "B.SilkS")
		)
		(fp_line
			(start 0.7874 -0.4064)
			(end -0.7874 -0.4064)
			(stroke
				(width 0.1524)
				(type default)
			)
			(layer "B.SilkS")
		)
		(fp_line
			(start -0.7874 0.4064)
			(end 0.7874 0.4064)
			(stroke
				(width 0.1524)
				(type default)
			)
			(layer "B.SilkS")
		)
		(fp_line
			(start -0.7874 -0.4064)
			(end -0.7874 0.4064)
			(stroke
				(width 0.1524)
				(type default)
			)
			(layer "B.SilkS")
		)
		(fp_line
			(start 0.67945 0.3048)
			(end 0.67945 -0.305054)
			(stroke
				(width 0.1)
				(type default)
			)
			(layer "B.Fab")
		)
		(fp_line
			(start 0.67945 -0.305054)
			(end 0.12065 -0.305054)
			(stroke
				(width 0.1)
				(type default)
			)
			(layer "B.Fab")
		)
		(fp_line
			(start 0.12065 0.3048)
			(end 0.67945 0.3048)
			(stroke
				(width 0.1)
				(type default)
			)
			(layer "B.Fab")
		)
		(fp_line
			(start 0.12065 0.2794)
			(end 0.12065 0.3048)
			(stroke
				(width 0.1)
				(type default)
			)
			(layer "B.Fab")
		)
		(fp_line
			(start 0.12065 -0.2794)
			(end -0.12065 -0.2794)
			(stroke
				(width 0.1)
				(type default)
			)
			(layer "B.Fab")
		)
		(fp_line
			(start 0.12065 -0.305054)
			(end 0.12065 -0.2794)
			(stroke
				(width 0.1)
				(type default)
			)
			(layer "B.Fab")
		)
		(fp_line
			(start -0.120396 0.3048)
			(end -0.120396 0.2794)
			(stroke
				(width 0.1)
				(type default)
			)
			(layer "B.Fab")
		)
		(fp_line
			(start -0.120396 0.2794)
			(end 0.12065 0.2794)
			(stroke
				(width 0.1)
				(type default)
			)
			(layer "B.Fab")
		)
		(fp_line
			(start -0.12065 -0.2794)
			(end -0.12065 -0.3048)
			(stroke
				(width 0.1)
				(type default)
			)
			(layer "B.Fab")
		)
		(fp_line
			(start -0.12065 -0.3048)
			(end -0.67945 -0.3048)
			(stroke
				(width 0.1)
				(type default)
			)
			(layer "B.Fab")
		)
		(fp_line
			(start -0.67945 0.3048)
			(end -0.120396 0.3048)
			(stroke
				(width 0.1)
				(type default)
			)
			(layer "B.Fab")
		)
		(fp_line
			(start -0.67945 -0.3048)
			(end -0.67945 0.3048)
			(stroke
				(width 0.1)
				(type default)
			)
			(layer "B.Fab")
		)
		(pad "1" smd circle
			(at 0.40005 0)
			(size 0 0)
			(layers "B.Cu" "B.Mask" "B.Paste")
			(net "P3V3_E1S_UV_0_R")
		)
		(pad "2" smd circle
			(at -0.40005 0)
			(size 0 0)
			(layers "B.Cu" "B.Mask" "B.Paste")
			(net "P3V3_E1S_UV_0")
		)
	)
	(footprint ""
		(layer "B.Cu")
		(at 399.670778 -190.77559 90)
		(property "Reference" "R179"
			(at 0 0 90)
			(layer "B.SilkS")
			(hide yes)
			(effects
				(font
					(size 1.27 1.27)
				)
				(justify mirror)
			)
		)
		(property "Value" ""
			(at 0 0 90)
			(layer "B.Fab")
			(effects
				(font
					(size 1.27 1.27)
				)
				(justify mirror)
			)
		)
		(duplicate_pad_numbers_are_jumpers no)
		(fp_line
			(start 0.7874 -0.4064)
			(end -0.7874 -0.4064)
			(stroke
				(width 0.1524)
				(type default)
			)
			(layer "B.SilkS")
		)
		(fp_line
			(start -0.7874 -0.4064)
			(end -0.7874 0.4064)
			(stroke
				(width 0.1524)
				(type default)
			)
			(layer "B.SilkS")
		)
		(fp_line
			(start 0.7874 0.4064)
			(end 0.7874 -0.4064)
			(stroke
				(width 0.1524)
				(type default)
			)
			(layer "B.SilkS")
		)
		(fp_line
			(start -0.7874 0.4064)
			(end 0.7874 0.4064)
			(stroke
				(width 0.1524)
				(type default)
			)
			(layer "B.SilkS")
		)
		(fp_line
			(start 0.67945 -0.305054)
			(end 0.12065 -0.305054)
			(stroke
				(width 0.1)
				(type default)
			)
			(layer "B.Fab")
		)
		(fp_line
			(start 0.12065 -0.305054)
			(end 0.12065 -0.2794)
			(stroke
				(width 0.1)
				(type default)
			)
			(layer "B.Fab")
		)
		(fp_line
			(start -0.12065 -0.3048)
			(end -0.67945 -0.3048)
			(stroke
				(width 0.1)
				(type default)
			)
			(layer "B.Fab")
		)
		(fp_line
			(start -0.67945 -0.3048)
			(end -0.67945 0.3048)
			(stroke
				(width 0.1)
				(type default)
			)
			(layer "B.Fab")
		)
		(fp_line
			(start 0.12065 -0.2794)
			(end -0.12065 -0.2794)
			(stroke
				(width 0.1)
				(type default)
			)
			(layer "B.Fab")
		)
		(fp_line
			(start -0.12065 -0.2794)
			(end -0.12065 -0.3048)
			(stroke
				(width 0.1)
				(type default)
			)
			(layer "B.Fab")
		)
		(fp_line
			(start 0.12065 0.2794)
			(end 0.12065 0.3048)
			(stroke
				(width 0.1)
				(type default)
			)
			(layer "B.Fab")
		)
		(fp_line
			(start -0.120396 0.2794)
			(end 0.12065 0.2794)
			(stroke
				(width 0.1)
				(type default)
			)
			(layer "B.Fab")
		)
		(fp_line
			(start 0.67945 0.3048)
			(end 0.67945 -0.305054)
			(stroke
				(width 0.1)
				(type default)
			)
			(layer "B.Fab")
		)
		(fp_line
			(start 0.12065 0.3048)
			(end 0.67945 0.3048)
			(stroke
				(width 0.1)
				(type default)
			)
			(layer "B.Fab")
		)
		(fp_line
			(start -0.120396 0.3048)
			(end -0.120396 0.2794)
			(stroke
				(width 0.1)
				(type default)
			)
			(layer "B.Fab")
		)
		(fp_line
			(start -0.67945 0.3048)
			(end -0.120396 0.3048)
			(stroke
				(width 0.1)
				(type default)
			)
			(layer "B.Fab")
		)
		(pad "1" smd circle
			(at 0.40005 0 270)
			(size 0 0)
			(layers "B.Cu" "B.Mask" "B.Paste")
			(net "PWRGD_DRAMPWRGD_CPU0_EF_LVC1_R2")
		)
		(pad "2" smd circle
			(at -0.40005 0 270)
			(size 0 0)
			(layers "B.Cu" "B.Mask" "B.Paste")
			(net "PVCCD_HV_CPU0")
		)
	)
	(footprint ""
		(layer "B.Cu")
		(at 160.83788 -120.106948)
		(property "Reference" "R985"
			(at 0 0 0)
			(layer "B.SilkS")
			(hide yes)
			(effects
				(font
					(size 1.27 1.27)
				)
				(justify mirror)
			)
		)
		(property "Value" ""
			(at 0 0 0)
			(layer "B.Fab")
			(effects
				(font
					(size 1.27 1.27)
				)
				(justify mirror)
			)
		)
		(duplicate_pad_numbers_are_jumpers no)
		(fp_line
			(start -0.7874 -0.4064)
			(end -0.7874 0.4064)
			(stroke
				(width 0.1524)
				(type default)
			)
			(layer "B.SilkS")
		)
		(fp_line
			(start -0.7874 0.4064)
			(end 0.7874 0.4064)
			(stroke
				(width 0.1524)
				(type default)
			)
			(layer "B.SilkS")
		)
		(fp_line
			(start 0.7874 -0.4064)
			(end -0.7874 -0.4064)
			(stroke
				(width 0.1524)
				(type default)
			)
			(layer "B.SilkS")
		)
		(fp_line
			(start 0.7874 0.4064)
			(end 0.7874 -0.4064)
			(stroke
				(width 0.1524)
				(type default)
			)
			(layer "B.SilkS")
		)
		(fp_line
			(start -0.67945 -0.3048)
			(end -0.67945 0.3048)
			(stroke
				(width 0.1)
				(type default)
			)
			(layer "B.Fab")
		)
		(fp_line
			(start -0.67945 0.3048)
			(end -0.120396 0.3048)
			(stroke
				(width 0.1)
				(type default)
			)
			(layer "B.Fab")
		)
		(fp_line
			(start -0.12065 -0.3048)
			(end -0.67945 -0.3048)
			(stroke
				(width 0.1)
				(type default)
			)
			(layer "B.Fab")
		)
		(fp_line
			(start -0.12065 -0.2794)
			(end -0.12065 -0.3048)
			(stroke
				(width 0.1)
				(type default)
			)
			(layer "B.Fab")
		)
		(fp_line
			(start -0.120396 0.2794)
			(end 0.12065 0.2794)
			(stroke
				(width 0.1)
				(type default)
			)
			(layer "B.Fab")
		)
		(fp_line
			(start -0.120396 0.3048)
			(end -0.120396 0.2794)
			(stroke
				(width 0.1)
				(type default)
			)
			(layer "B.Fab")
		)
		(fp_line
			(start 0.12065 -0.305054)
			(end 0.12065 -0.2794)
			(stroke
				(width 0.1)
				(type default)
			)
			(layer "B.Fab")
		)
		(fp_line
			(start 0.12065 -0.2794)
			(end -0.12065 -0.2794)
			(stroke
				(width 0.1)
				(type default)
			)
			(layer "B.Fab")
		)
		(fp_line
			(start 0.12065 0.2794)
			(end 0.12065 0.3048)
			(stroke
				(width 0.1)
				(type default)
			)
			(layer "B.Fab")
		)
		(fp_line
			(start 0.12065 0.3048)
			(end 0.67945 0.3048)
			(stroke
				(width 0.1)
				(type default)
			)
			(layer "B.Fab")
		)
		(fp_line
			(start 0.67945 -0.305054)
			(end 0.12065 -0.305054)
			(stroke
				(width 0.1)
				(type default)
			)
			(layer "B.Fab")
		)
		(fp_line
			(start 0.67945 0.3048)
			(end 0.67945 -0.305054)
			(stroke
				(width 0.1)
				(type default)
			)
			(layer "B.Fab")
		)
		(pad "1" smd circle
			(at 0.40005 0 180)
			(size 0 0)
			(layers "B.Cu" "B.Mask" "B.Paste")
			(net "FM_PVCCIN_CPU1_R_EN")
		)
		(pad "2" smd circle
			(at -0.40005 0 180)
			(size 0 0)
			(layers "B.Cu" "B.Mask" "B.Paste")
			(net "FM_PVCCIN_CPU1_EN")
		)
	)
	(footprint ""
		(layer "B.Cu")
		(at 351.841308 -252.176026 -90)
		(property "Reference" "C365"
			(at 0 0 90)
			(layer "B.SilkS")
			(hide yes)
			(effects
				(font
					(size 1.27 1.27)
				)
				(justify mirror)
			)
		)
		(property "Value" ""
			(at 0 0 90)
			(layer "B.Fab")
			(effects
				(font
					(size 1.27 1.27)
				)
				(justify mirror)
			)
		)
		(duplicate_pad_numbers_are_jumpers no)
		(fp_line
			(start -1.524 0.762)
			(end 1.524 0.762)
			(stroke
				(width 0.1524)
				(type default)
			)
			(layer "B.SilkS")
		)
		(fp_line
			(start 1.524 0.762)
			(end 1.524 -0.762)
			(stroke
				(width 0.1524)
				(type default)
			)
			(layer "B.SilkS")
		)
		(fp_line
			(start -1.524 -0.762)
			(end -1.524 0.762)
			(stroke
				(width 0.1524)
				(type default)
			)
			(layer "B.SilkS")
		)
		(fp_line
			(start 1.524 -0.762)
			(end -1.524 -0.762)
			(stroke
				(width 0.1524)
				(type default)
			)
			(layer "B.SilkS")
		)
		(fp_line
			(start -1.1049 0.724916)
			(end -1.1049 -0.724916)
			(stroke
				(width 0.1)
				(type default)
			)
			(layer "B.Fab")
		)
		(fp_line
			(start 1.1049 0.724916)
			(end -1.1049 0.724916)
			(stroke
				(width 0.1)
				(type default)
			)
			(layer "B.Fab")
		)
		(fp_line
			(start -1.1049 -0.724916)
			(end 1.1049 -0.724916)
			(stroke
				(width 0.1)
				(type default)
			)
			(layer "B.Fab")
		)
		(fp_line
			(start 1.1049 -0.724916)
			(end 1.1049 0.724916)
			(stroke
				(width 0.1)
				(type default)
			)
			(layer "B.Fab")
		)
		(pad "1" smd rect
			(at 0.889 0 270)
			(size 1.016 1.27)
			(layers "B.Cu" "B.Mask" "B.Paste")
			(net "PVCCIN_CPU0")
		)
		(pad "2" smd rect
			(at -0.889 0 270)
			(size 1.016 1.27)
			(layers "B.Cu" "B.Mask" "B.Paste")
			(net "GND")
		)
	)
)
